(kicad_pcb
	(version 20260206)
	(generator "pcbnew")
	(generator_version "10.0")
	(general
		(thickness 1.6)
		(legacy_teardrops no)
	)
	(paper "A4")
	(title_block
		(title "04192023_DAF0TMB3IC0_F0TG_MB_C_brd_V02_OCP.brd")
		(comment 1 "Grand Teton / footprints 7499-7504 of 8354")
	)
	(layers
		(0 "F.Cu" signal "TOP")
		(4 "In1.Cu" signal "GND")
		(6 "In2.Cu" signal "IN1")
		(8 "In3.Cu" signal "GND1")
		(10 "In4.Cu" signal "IN2")
		(12 "In5.Cu" signal "GND2")
		(14 "In6.Cu" signal "IN3")
		(16 "In7.Cu" signal "GND3")
		(18 "In8.Cu" signal "VCC")
		(20 "In9.Cu" signal "VCC1")
		(22 "In10.Cu" signal "GND4")
		(24 "In11.Cu" signal "IN4")
		(26 "In12.Cu" signal "GND5")
		(28 "In13.Cu" signal "IN5")
		(30 "In14.Cu" signal "GND6")
		(32 "In15.Cu" signal "IN6")
		(34 "In16.Cu" signal "GND7")
		(2 "B.Cu" signal "BOTTOM")
		(9 "F.Adhes" user "F.Adhesive")
		(11 "B.Adhes" user "B.Adhesive")
		(13 "F.Paste" user "Package Geometry/Pastemask Top")
		(15 "B.Paste" user "Package Geometry/Pastemask Bottom")
		(5 "F.SilkS" user "Ref Des/Silkscreen Top")
		(7 "B.SilkS" user "Ref Des/Silkscreen Bottom")
		(1 "F.Mask" user "Board Geometry/Soldermask Top")
		(3 "B.Mask" user "Board Geometry/Soldermask Bottom")
		(17 "Dwgs.User" user "User.Drawings")
		(19 "Cmts.User" user "User.Comments")
		(21 "Eco1.User" user "User.Eco1")
		(23 "Eco2.User" user "User.Eco2")
		(25 "Edge.Cuts" user "Board Geometry/Outline")
		(27 "Margin" user)
		(31 "F.CrtYd" user "Package Geometry/Place Bound Top")
		(29 "B.CrtYd" user "Package Geometry/Place Bound Bottom")
		(35 "F.Fab" user "Ref Des/Assembly Top")
		(33 "B.Fab" user "Ref Des/Assembly Bottom")
	)
	(footprint ""
		(layer "B.Cu")
		(at 182.801768 -414.772094 180)
		(property "Reference" "R2924"
			(at 0 0 0)
			(layer "B.SilkS")
			(hide yes)
			(effects
				(font
					(size 1.27 1.27)
				)
				(justify mirror)
			)
		)
		(property "Value" ""
			(at 0 0 0)
			(layer "B.Fab")
			(effects
				(font
					(size 1.27 1.27)
				)
				(justify mirror)
			)
		)
		(duplicate_pad_numbers_are_jumpers no)
		(fp_line
			(start 0.7874 0.4064)
			(end 0.7874 -0.4064)
			(stroke
				(width 0.1524)
				(type default)
			)
			(layer "B.SilkS")
		)
		(fp_line
			(start 0.7874 -0.4064)
			(end -0.7874 -0.4064)
			(stroke
				(width 0.1524)
				(type default)
			)
			(layer "B.SilkS")
		)
		(fp_line
			(start -0.7874 0.4064)
			(end 0.7874 0.4064)
			(stroke
				(width 0.1524)
				(type default)
			)
			(layer "B.SilkS")
		)
		(fp_line
			(start -0.7874 -0.4064)
			(end -0.7874 0.4064)
			(stroke
				(width 0.1524)
				(type default)
			)
			(layer "B.SilkS")
		)
		(fp_line
			(start 0.67945 0.3048)
			(end 0.67945 -0.305054)
			(stroke
				(width 0.1)
				(type default)
			)
			(layer "B.Fab")
		)
		(fp_line
			(start 0.67945 -0.305054)
			(end 0.12065 -0.305054)
			(stroke
				(width 0.1)
				(type default)
			)
			(layer "B.Fab")
		)
		(fp_line
			(start 0.12065 0.3048)
			(end 0.67945 0.3048)
			(stroke
				(width 0.1)
				(type default)
			)
			(layer "B.Fab")
		)
		(fp_line
			(start 0.12065 0.2794)
			(end 0.12065 0.3048)
			(stroke
				(width 0.1)
				(type default)
			)
			(layer "B.Fab")
		)
		(fp_line
			(start 0.12065 -0.2794)
			(end -0.12065 -0.2794)
			(stroke
				(width 0.1)
				(type default)
			)
			(layer "B.Fab")
		)
		(fp_line
			(start 0.12065 -0.305054)
			(end 0.12065 -0.2794)
			(stroke
				(width 0.1)
				(type default)
			)
			(layer "B.Fab")
		)
		(fp_line
			(start -0.120396 0.3048)
			(end -0.120396 0.2794)
			(stroke
				(width 0.1)
				(type default)
			)
			(layer "B.Fab")
		)
		(fp_line
			(start -0.120396 0.2794)
			(end 0.12065 0.2794)
			(stroke
				(width 0.1)
				(type default)
			)
			(layer "B.Fab")
		)
		(fp_line
			(start -0.12065 -0.2794)
			(end -0.12065 -0.3048)
			(stroke
				(width 0.1)
				(type default)
			)
			(layer "B.Fab")
		)
		(fp_line
			(start -0.12065 -0.3048)
			(end -0.67945 -0.3048)
			(stroke
				(width 0.1)
				(type default)
			)
			(layer "B.Fab")
		)
		(fp_line
			(start -0.67945 0.3048)
			(end -0.120396 0.3048)
			(stroke
				(width 0.1)
				(type default)
			)
			(layer "B.Fab")
		)
		(fp_line
			(start -0.67945 -0.3048)
			(end -0.67945 0.3048)
			(stroke
				(width 0.1)
				(type default)
			)
			(layer "B.Fab")
		)
		(pad "1" smd circle
			(at 0.40005 0)
			(size 0 0)
			(layers "B.Cu" "B.Mask" "B.Paste")
			(net "RST_SWB_BIC_BUF_R_N")
		)
		(pad "2" smd circle
			(at -0.40005 0)
			(size 0 0)
			(layers "B.Cu" "B.Mask" "B.Paste")
			(net "RST_SWB_BIC_BUF_N")
		)
	)
	(footprint ""
		(layer "B.Cu")
		(at 188.935614 -352.380042 -90)
		(property "Reference" "PR327"
			(at 0 0 90)
			(layer "B.SilkS")
			(hide yes)
			(effects
				(font
					(size 1.27 1.27)
				)
				(justify mirror)
			)
		)
		(property "Value" ""
			(at 0 0 90)
			(layer "B.Fab")
			(effects
				(font
					(size 1.27 1.27)
				)
				(justify mirror)
			)
		)
		(duplicate_pad_numbers_are_jumpers no)
		(fp_line
			(start -0.7874 0.4064)
			(end 0.7874 0.4064)
			(stroke
				(width 0.1524)
				(type default)
			)
			(layer "B.SilkS")
		)
		(fp_line
			(start 0.7874 0.4064)
			(end 0.7874 -0.4064)
			(stroke
				(width 0.1524)
				(type default)
			)
			(layer "B.SilkS")
		)
		(fp_line
			(start -0.7874 -0.4064)
			(end -0.7874 0.4064)
			(stroke
				(width 0.1524)
				(type default)
			)
			(layer "B.SilkS")
		)
		(fp_line
			(start 0.7874 -0.4064)
			(end -0.7874 -0.4064)
			(stroke
				(width 0.1524)
				(type default)
			)
			(layer "B.SilkS")
		)
		(fp_line
			(start -0.67945 0.3048)
			(end -0.120396 0.3048)
			(stroke
				(width 0.1)
				(type default)
			)
			(layer "B.Fab")
		)
		(fp_line
			(start -0.120396 0.3048)
			(end -0.120396 0.2794)
			(stroke
				(width 0.1)
				(type default)
			)
			(layer "B.Fab")
		)
		(fp_line
			(start 0.12065 0.3048)
			(end 0.67945 0.3048)
			(stroke
				(width 0.1)
				(type default)
			)
			(layer "B.Fab")
		)
		(fp_line
			(start 0.67945 0.3048)
			(end 0.67945 -0.305054)
			(stroke
				(width 0.1)
				(type default)
			)
			(layer "B.Fab")
		)
		(fp_line
			(start -0.120396 0.2794)
			(end 0.12065 0.2794)
			(stroke
				(width 0.1)
				(type default)
			)
			(layer "B.Fab")
		)
		(fp_line
			(start 0.12065 0.2794)
			(end 0.12065 0.3048)
			(stroke
				(width 0.1)
				(type default)
			)
			(layer "B.Fab")
		)
		(fp_line
			(start -0.12065 -0.2794)
			(end -0.12065 -0.3048)
			(stroke
				(width 0.1)
				(type default)
			)
			(layer "B.Fab")
		)
		(fp_line
			(start 0.12065 -0.2794)
			(end -0.12065 -0.2794)
			(stroke
				(width 0.1)
				(type default)
			)
			(layer "B.Fab")
		)
		(fp_line
			(start -0.67945 -0.3048)
			(end -0.67945 0.3048)
			(stroke
				(width 0.1)
				(type default)
			)
			(layer "B.Fab")
		)
		(fp_line
			(start -0.12065 -0.3048)
			(end -0.67945 -0.3048)
			(stroke
				(width 0.1)
				(type default)
			)
			(layer "B.Fab")
		)
		(fp_line
			(start 0.12065 -0.305054)
			(end 0.12065 -0.2794)
			(stroke
				(width 0.1)
				(type default)
			)
			(layer "B.Fab")
		)
		(fp_line
			(start 0.67945 -0.305054)
			(end 0.12065 -0.305054)
			(stroke
				(width 0.1)
				(type default)
			)
			(layer "B.Fab")
		)
		(pad "1" smd circle
			(at 0.40005 0 90)
			(size 0 0)
			(layers "B.Cu" "B.Mask" "B.Paste")
			(net "PVDD11_S3_P1_PVCC")
		)
		(pad "2" smd circle
			(at -0.40005 0 90)
			(size 0 0)
			(layers "B.Cu" "B.Mask" "B.Paste")
			(net "PVDD11_S3_P1_VCC2")
		)
	)
	(footprint ""
		(layer "B.Cu")
		(at 88.177878 -150.19909)
		(property "Reference" "PR150"
			(at 0 0 0)
			(layer "B.SilkS")
			(hide yes)
			(effects
				(font
					(size 1.27 1.27)
				)
				(justify mirror)
			)
		)
		(property "Value" ""
			(at 0 0 0)
			(layer "B.Fab")
			(effects
				(font
					(size 1.27 1.27)
				)
				(justify mirror)
			)
		)
		(duplicate_pad_numbers_are_jumpers no)
		(fp_line
			(start -0.7874 -0.4064)
			(end -0.7874 0.4064)
			(stroke
				(width 0.1524)
				(type default)
			)
			(layer "B.SilkS")
		)
		(fp_line
			(start -0.7874 0.4064)
			(end 0.7874 0.4064)
			(stroke
				(width 0.1524)
				(type default)
			)
			(layer "B.SilkS")
		)
		(fp_line
			(start 0.7874 -0.4064)
			(end -0.7874 -0.4064)
			(stroke
				(width 0.1524)
				(type default)
			)
			(layer "B.SilkS")
		)
		(fp_line
			(start 0.7874 0.4064)
			(end 0.7874 -0.4064)
			(stroke
				(width 0.1524)
				(type default)
			)
			(layer "B.SilkS")
		)
		(fp_line
			(start -0.67945 -0.3048)
			(end -0.67945 0.3048)
			(stroke
				(width 0.1)
				(type default)
			)
			(layer "B.Fab")
		)
		(fp_line
			(start -0.67945 0.3048)
			(end -0.120396 0.3048)
			(stroke
				(width 0.1)
				(type default)
			)
			(layer "B.Fab")
		)
		(fp_line
			(start -0.12065 -0.3048)
			(end -0.67945 -0.3048)
			(stroke
				(width 0.1)
				(type default)
			)
			(layer "B.Fab")
		)
		(fp_line
			(start -0.12065 -0.2794)
			(end -0.12065 -0.3048)
			(stroke
				(width 0.1)
				(type default)
			)
			(layer "B.Fab")
		)
		(fp_line
			(start -0.120396 0.2794)
			(end 0.12065 0.2794)
			(stroke
				(width 0.1)
				(type default)
			)
			(layer "B.Fab")
		)
		(fp_line
			(start -0.120396 0.3048)
			(end -0.120396 0.2794)
			(stroke
				(width 0.1)
				(type default)
			)
			(layer "B.Fab")
		)
		(fp_line
			(start 0.12065 -0.305054)
			(end 0.12065 -0.2794)
			(stroke
				(width 0.1)
				(type default)
			)
			(layer "B.Fab")
		)
		(fp_line
			(start 0.12065 -0.2794)
			(end -0.12065 -0.2794)
			(stroke
				(width 0.1)
				(type default)
			)
			(layer "B.Fab")
		)
		(fp_line
			(start 0.12065 0.2794)
			(end 0.12065 0.3048)
			(stroke
				(width 0.1)
				(type default)
			)
			(layer "B.Fab")
		)
		(fp_line
			(start 0.12065 0.3048)
			(end 0.67945 0.3048)
			(stroke
				(width 0.1)
				(type default)
			)
			(layer "B.Fab")
		)
		(fp_line
			(start 0.67945 -0.305054)
			(end 0.12065 -0.305054)
			(stroke
				(width 0.1)
				(type default)
			)
			(layer "B.Fab")
		)
		(fp_line
			(start 0.67945 0.3048)
			(end 0.67945 -0.305054)
			(stroke
				(width 0.1)
				(type default)
			)
			(layer "B.Fab")
		)
		(pad "1" smd circle
			(at 0.40005 0 180)
			(size 0 0)
			(layers "B.Cu" "B.Mask" "B.Paste")
			(net "SVID_PVDDCR_CPU0_P1_SVTI")
		)
		(pad "2" smd circle
			(at -0.40005 0 180)
			(size 0 0)
			(layers "B.Cu" "B.Mask" "B.Paste")
			(net "GND")
		)
	)
	(footprint ""
		(layer "B.Cu")
		(at 237.923578 -323.585332)
		(property "Reference" "R1232"
			(at 0 0 0)
			(layer "B.SilkS")
			(hide yes)
			(effects
				(font
					(size 1.27 1.27)
				)
				(justify mirror)
			)
		)
		(property "Value" ""
			(at 0 0 0)
			(layer "B.Fab")
			(effects
				(font
					(size 1.27 1.27)
				)
				(justify mirror)
			)
		)
		(duplicate_pad_numbers_are_jumpers no)
		(fp_line
			(start -0.7874 -0.4064)
			(end -0.7874 0.4064)
			(stroke
				(width 0.1524)
				(type default)
			)
			(layer "B.SilkS")
		)
		(fp_line
			(start -0.7874 0.4064)
			(end 0.7874 0.4064)
			(stroke
				(width 0.1524)
				(type default)
			)
			(layer "B.SilkS")
		)
		(fp_line
			(start 0.7874 -0.4064)
			(end -0.7874 -0.4064)
			(stroke
				(width 0.1524)
				(type default)
			)
			(layer "B.SilkS")
		)
		(fp_line
			(start 0.7874 0.4064)
			(end 0.7874 -0.4064)
			(stroke
				(width 0.1524)
				(type default)
			)
			(layer "B.SilkS")
		)
		(fp_line
			(start -0.67945 -0.3048)
			(end -0.67945 0.3048)
			(stroke
				(width 0.1)
				(type default)
			)
			(layer "B.Fab")
		)
		(fp_line
			(start -0.67945 0.3048)
			(end -0.120396 0.3048)
			(stroke
				(width 0.1)
				(type default)
			)
			(layer "B.Fab")
		)
		(fp_line
			(start -0.12065 -0.3048)
			(end -0.67945 -0.3048)
			(stroke
				(width 0.1)
				(type default)
			)
			(layer "B.Fab")
		)
		(fp_line
			(start -0.12065 -0.2794)
			(end -0.12065 -0.3048)
			(stroke
				(width 0.1)
				(type default)
			)
			(layer "B.Fab")
		)
		(fp_line
			(start -0.120396 0.2794)
			(end 0.12065 0.2794)
			(stroke
				(width 0.1)
				(type default)
			)
			(layer "B.Fab")
		)
		(fp_line
			(start -0.120396 0.3048)
			(end -0.120396 0.2794)
			(stroke
				(width 0.1)
				(type default)
			)
			(layer "B.Fab")
		)
		(fp_line
			(start 0.12065 -0.305054)
			(end 0.12065 -0.2794)
			(stroke
				(width 0.1)
				(type default)
			)
			(layer "B.Fab")
		)
		(fp_line
			(start 0.12065 -0.2794)
			(end -0.12065 -0.2794)
			(stroke
				(width 0.1)
				(type default)
			)
			(layer "B.Fab")
		)
		(fp_line
			(start 0.12065 0.2794)
			(end 0.12065 0.3048)
			(stroke
				(width 0.1)
				(type default)
			)
			(layer "B.Fab")
		)
		(fp_line
			(start 0.12065 0.3048)
			(end 0.67945 0.3048)
			(stroke
				(width 0.1)
				(type default)
			)
			(layer "B.Fab")
		)
		(fp_line
			(start 0.67945 -0.305054)
			(end 0.12065 -0.305054)
			(stroke
				(width 0.1)
				(type default)
			)
			(layer "B.Fab")
		)
		(fp_line
			(start 0.67945 0.3048)
			(end 0.67945 -0.305054)
			(stroke
				(width 0.1)
				(type default)
			)
			(layer "B.Fab")
		)
		(pad "1" smd circle
			(at 0.40005 0 180)
			(size 0 0)
			(layers "B.Cu" "B.Mask" "B.Paste")
			(net "P1V2_AUX")
		)
		(pad "2" smd circle
			(at -0.40005 0 180)
			(size 0 0)
			(layers "B.Cu" "B.Mask" "B.Paste")
			(net "P1V2_AUX_ADC")
		)
	)
	(footprint ""
		(layer "B.Cu")
		(at 183.557164 -23.655782 -90)
		(property "Reference" "R3240"
			(at 0 0 90)
			(layer "B.SilkS")
			(hide yes)
			(effects
				(font
					(size 1.27 1.27)
				)
				(justify mirror)
			)
		)
		(property "Value" ""
			(at 0 0 90)
			(layer "B.Fab")
			(effects
				(font
					(size 1.27 1.27)
				)
				(justify mirror)
			)
		)
		(duplicate_pad_numbers_are_jumpers no)
		(fp_line
			(start -0.7874 0.4064)
			(end 0.7874 0.4064)
			(stroke
				(width 0.1524)
				(type default)
			)
			(layer "B.SilkS")
		)
		(fp_line
			(start 0.7874 0.4064)
			(end 0.7874 -0.4064)
			(stroke
				(width 0.1524)
				(type default)
			)
			(layer "B.SilkS")
		)
		(fp_line
			(start -0.7874 -0.4064)
			(end -0.7874 0.4064)
			(stroke
				(width 0.1524)
				(type default)
			)
			(layer "B.SilkS")
		)
		(fp_line
			(start 0.7874 -0.4064)
			(end -0.7874 -0.4064)
			(stroke
				(width 0.1524)
				(type default)
			)
			(layer "B.SilkS")
		)
		(fp_line
			(start -0.67945 0.3048)
			(end -0.120396 0.3048)
			(stroke
				(width 0.1)
				(type default)
			)
			(layer "B.Fab")
		)
		(fp_line
			(start -0.120396 0.3048)
			(end -0.120396 0.2794)
			(stroke
				(width 0.1)
				(type default)
			)
			(layer "B.Fab")
		)
		(fp_line
			(start 0.12065 0.3048)
			(end 0.67945 0.3048)
			(stroke
				(width 0.1)
				(type default)
			)
			(layer "B.Fab")
		)
		(fp_line
			(start 0.67945 0.3048)
			(end 0.67945 -0.305054)
			(stroke
				(width 0.1)
				(type default)
			)
			(layer "B.Fab")
		)
		(fp_line
			(start -0.120396 0.2794)
			(end 0.12065 0.2794)
			(stroke
				(width 0.1)
				(type default)
			)
			(layer "B.Fab")
		)
		(fp_line
			(start 0.12065 0.2794)
			(end 0.12065 0.3048)
			(stroke
				(width 0.1)
				(type default)
			)
			(layer "B.Fab")
		)
		(fp_line
			(start -0.12065 -0.2794)
			(end -0.12065 -0.3048)
			(stroke
				(width 0.1)
				(type default)
			)
			(layer "B.Fab")
		)
		(fp_line
			(start 0.12065 -0.2794)
			(end -0.12065 -0.2794)
			(stroke
				(width 0.1)
				(type default)
			)
			(layer "B.Fab")
		)
		(fp_line
			(start -0.67945 -0.3048)
			(end -0.67945 0.3048)
			(stroke
				(width 0.1)
				(type default)
			)
			(layer "B.Fab")
		)
		(fp_line
			(start -0.12065 -0.3048)
			(end -0.67945 -0.3048)
			(stroke
				(width 0.1)
				(type default)
			)
			(layer "B.Fab")
		)
		(fp_line
			(start 0.12065 -0.305054)
			(end 0.12065 -0.2794)
			(stroke
				(width 0.1)
				(type default)
			)
			(layer "B.Fab")
		)
		(fp_line
			(start 0.67945 -0.305054)
			(end 0.12065 -0.305054)
			(stroke
				(width 0.1)
				(type default)
			)
			(layer "B.Fab")
		)
		(pad "1" smd circle
			(at 0.40005 0 90)
			(size 0 0)
			(layers "B.Cu" "B.Mask" "B.Paste")
			(net "SMB_OCP_SFF_3V3AUX_SCL")
		)
		(pad "2" smd circle
			(at -0.40005 0 90)
			(size 0 0)
			(layers "B.Cu" "B.Mask" "B.Paste")
			(net "P3V3_AUX")
		)
	)
	(footprint ""
		(layer "B.Cu")
		(at 439.100214 -192.660016)
		(property "Reference" "C166"
			(at 0 0 0)
			(layer "B.SilkS")
			(hide yes)
			(effects
				(font
					(size 1.27 1.27)
				)
				(justify mirror)
			)
		)
		(property "Value" ""
			(at 0 0 0)
			(layer "B.Fab")
			(effects
				(font
					(size 1.27 1.27)
				)
				(justify mirror)
			)
		)
		(duplicate_pad_numbers_are_jumpers no)
		(fp_line
			(start -1.524 -0.762)
			(end -1.524 0.762)
			(stroke
				(width 0.1524)
				(type default)
			)
			(layer "B.SilkS")
		)
		(fp_line
			(start -1.524 0.762)
			(end 1.524 0.762)
			(stroke
				(width 0.1524)
				(type default)
			)
			(layer "B.SilkS")
		)
		(fp_line
			(start 1.524 -0.762)
			(end -1.524 -0.762)
			(stroke
				(width 0.1524)
				(type default)
			)
			(layer "B.SilkS")
		)
		(fp_line
			(start 1.524 0.762)
			(end 1.524 -0.762)
			(stroke
				(width 0.1524)
				(type default)
			)
			(layer "B.SilkS")
		)
		(fp_line
			(start -1.1049 -0.724916)
			(end 1.1049 -0.724916)
			(stroke
				(width 0.1)
				(type default)
			)
			(layer "B.Fab")
		)
		(fp_line
			(start -1.1049 0.724916)
			(end -1.1049 -0.724916)
			(stroke
				(width 0.1)
				(type default)
			)
			(layer "B.Fab")
		)
		(fp_line
			(start 1.1049 -0.724916)
			(end 1.1049 0.724916)
			(stroke
				(width 0.1)
				(type default)
			)
			(layer "B.Fab")
		)
		(fp_line
			(start 1.1049 0.724916)
			(end -1.1049 0.724916)
			(stroke
				(width 0.1)
				(type default)
			)
			(layer "B.Fab")
		)
		(pad "1" smd rect
			(at 0.889 0)
			(size 1.016 1.27)
			(layers "B.Cu" "B.Mask" "B.Paste")
			(net "P12V_MEM_CPU0")
		)
		(pad "2" smd rect
			(at -0.889 0)
			(size 1.016 1.27)
			(layers "B.Cu" "B.Mask" "B.Paste")
			(net "GND")
		)
	)
)
